# T6G (Grand Teton) — schematic netlist excerpt (pin names and nets, part order shuffled) for the footprints in the layout excerpt that follows; sources: Cadence DE-HDL packaged netlist, KiCad conversion of 04192023_DAF0TMB3IC0_F0TG_MB_C_brd_V02_OCP.brd

PC622_3  Q_CAP  0.1UF 25V 10% X7R  pkg 0402  page 223 : A = SW_P12V_AUX_PVDDIO_P1_FLT ; B = GND
C1553  Q_CAP_DIFFBUS  DIFF BUS_0.22UF 6.3V 20% X6S  pkg C0201  page 65 : \1\ = P5E_CPU0_G3_TX_C_DP<13> ; \2\ = P5E_CPU0_G3_TX_DP<13>
C6026  Q_CAP  0.1UF 25V 10% X7R  pkg 0402  page 180 : A = USB3_CPU0_BMC_HUB2_TX_DN ; B = USB3_CPU0_BMC_TX_BUF_C_DN

(kicad_pcb
	(version 20260206)
	(generator "pcbnew")
	(generator_version "10.0")
	(general
		(thickness 1.6)
		(legacy_teardrops no)
	)
	(paper "A4")
	(title_block
		(title "04192023_DAF0TMB3IC0_F0TG_MB_C_brd_V02_OCP.brd")
		(comment 1 "Grand Teton / footprints 3842-3845 of 8354")
	)
	(layers
		(0 "F.Cu" signal "TOP")
		(4 "In1.Cu" signal "GND")
		(6 "In2.Cu" signal "IN1")
		(8 "In3.Cu" signal "GND1")
		(10 "In4.Cu" signal "IN2")
		(12 "In5.Cu" signal "GND2")
		(14 "In6.Cu" signal "IN3")
		(16 "In7.Cu" signal "GND3")
		(18 "In8.Cu" signal "VCC")
		(20 "In9.Cu" signal "VCC1")
		(22 "In10.Cu" signal "GND4")
		(24 "In11.Cu" signal "IN4")
		(26 "In12.Cu" signal "GND5")
		(28 "In13.Cu" signal "IN5")
		(30 "In14.Cu" signal "GND6")
		(32 "In15.Cu" signal "IN6")
		(34 "In16.Cu" signal "GND7")
		(2 "B.Cu" signal "BOTTOM")
		(9 "F.Adhes" user "F.Adhesive")
		(11 "B.Adhes" user "B.Adhesive")
		(13 "F.Paste" user "Package Geometry/Pastemask Top")
		(15 "B.Paste" user "Package Geometry/Pastemask Bottom")
		(5 "F.SilkS" user "Ref Des/Silkscreen Top")
		(7 "B.SilkS" user "Ref Des/Silkscreen Bottom")
		(1 "F.Mask" user "Board Geometry/Soldermask Top")
		(3 "B.Mask" user "Board Geometry/Soldermask Bottom")
		(17 "Dwgs.User" user "User.Drawings")
		(19 "Cmts.User" user "User.Comments")
		(21 "Eco1.User" user "User.Eco1")
		(23 "Eco2.User" user "User.Eco2")
		(25 "Edge.Cuts" user "Board Geometry/Outline")
		(27 "Margin" user)
		(31 "F.CrtYd" user "Package Geometry/Place Bound Top")
		(29 "B.CrtYd" user "Package Geometry/Place Bound Bottom")
		(35 "F.Fab" user "Ref Des/Assembly Top")
		(33 "B.Fab" user "Ref Des/Assembly Bottom")
	)
	(footprint ""
		(layer "F.Cu")
		(at 122.55627 -35.430968)
		(property "Reference" "C6026"
			(at 0 0 0)
			(layer "F.SilkS")
			(hide yes)
			(effects
				(font
					(size 1.27 1.27)
				)
			)
		)
		(property "Value" ""
			(at 0 0 0)
			(layer "F.Fab")
			(effects
				(font
					(size 1.27 1.27)
				)
			)
		)
		(duplicate_pad_numbers_are_jumpers no)
		(fp_line
			(start -0.7874 -0.4064)
			(end 0.7874 -0.4064)
			(stroke
				(width 0.1524)
				(type default)
			)
			(layer "F.SilkS")
		)
		(fp_line
			(start -0.7874 0.4064)
			(end -0.7874 -0.4064)
			(stroke
				(width 0.1524)
				(type default)
			)
			(layer "F.SilkS")
		)
		(fp_line
			(start 0.7874 -0.4064)
			(end 0.7874 0.4064)
			(stroke
				(width 0.1524)
				(type default)
			)
			(layer "F.SilkS")
		)
		(fp_line
			(start 0.7874 0.4064)
			(end -0.7874 0.4064)
			(stroke
				(width 0.1524)
				(type default)
			)
			(layer "F.SilkS")
		)
		(fp_line
			(start -0.6858 -0.3048)
			(end -0.1016 -0.3048)
			(stroke
				(width 0.1)
				(type default)
			)
			(layer "F.Fab")
		)
		(fp_line
			(start -0.6858 0.3048)
			(end -0.6858 -0.3048)
			(stroke
				(width 0.1)
				(type default)
			)
			(layer "F.Fab")
		)
		(fp_line
			(start -0.1016 -0.3048)
			(end -0.1016 -0.2794)
			(stroke
				(width 0.1)
				(type default)
			)
			(layer "F.Fab")
		)
		(fp_line
			(start -0.1016 -0.2794)
			(end 0.1016 -0.2794)
			(stroke
				(width 0.1)
				(type default)
			)
			(layer "F.Fab")
		)
		(fp_line
			(start -0.1016 0.2794)
			(end -0.1016 0.3048)
			(stroke
				(width 0.1)
				(type default)
			)
			(layer "F.Fab")
		)
		(fp_line
			(start -0.1016 0.3048)
			(end -0.6858 0.3048)
			(stroke
				(width 0.1)
				(type default)
			)
			(layer "F.Fab")
		)
		(fp_line
			(start 0.1016 -0.3048)
			(end 0.6858 -0.3048)
			(stroke
				(width 0.1)
				(type default)
			)
			(layer "F.Fab")
		)
		(fp_line
			(start 0.1016 -0.2794)
			(end 0.1016 -0.3048)
			(stroke
				(width 0.1)
				(type default)
			)
			(layer "F.Fab")
		)
		(fp_line
			(start 0.1016 0.2794)
			(end -0.1016 0.2794)
			(stroke
				(width 0.1)
				(type default)
			)
			(layer "F.Fab")
		)
		(fp_line
			(start 0.1016 0.3048)
			(end 0.1016 0.2794)
			(stroke
				(width 0.1)
				(type default)
			)
			(layer "F.Fab")
		)
		(fp_line
			(start 0.6858 -0.3048)
			(end 0.6858 0.3048)
			(stroke
				(width 0.1)
				(type default)
			)
			(layer "F.Fab")
		)
		(fp_line
			(start 0.6858 0.3048)
			(end 0.1016 0.3048)
			(stroke
				(width 0.1)
				(type default)
			)
			(layer "F.Fab")
		)
		(pad "1" smd rect
			(at -0.40005 0 180)
			(size 0.4572 0.508)
			(layers "F.Cu" "F.Mask" "F.Paste")
			(net "USB3_CPU0_BMC_HUB2_TX_DN")
		)
		(pad "2" smd rect
			(at 0.40005 0 180)
			(size 0.4572 0.508)
			(layers "F.Cu" "F.Mask" "F.Paste")
			(net "USB3_CPU0_BMC_TX_BUF_C_DN")
		)
	)
	(footprint ""
		(layer "F.Cu")
		(at 32.744918 -351.10547)
		(property "Reference" "PC622_3"
			(at 0 0 0)
			(layer "F.SilkS")
			(hide yes)
			(effects
				(font
					(size 1.27 1.27)
				)
			)
		)
		(property "Value" ""
			(at 0 0 0)
			(layer "F.Fab")
			(effects
				(font
					(size 1.27 1.27)
				)
			)
		)
		(duplicate_pad_numbers_are_jumpers no)
		(fp_line
			(start -0.7874 -0.4064)
			(end 0.7874 -0.4064)
			(stroke
				(width 0.1524)
				(type default)
			)
			(layer "F.SilkS")
		)
		(fp_line
			(start -0.7874 0.4064)
			(end -0.7874 -0.4064)
			(stroke
				(width 0.1524)
				(type default)
			)
			(layer "F.SilkS")
		)
		(fp_line
			(start 0.7874 -0.4064)
			(end 0.7874 0.4064)
			(stroke
				(width 0.1524)
				(type default)
			)
			(layer "F.SilkS")
		)
		(fp_line
			(start 0.7874 0.4064)
			(end -0.7874 0.4064)
			(stroke
				(width 0.1524)
				(type default)
			)
			(layer "F.SilkS")
		)
		(fp_line
			(start -0.67945 -0.305054)
			(end -0.12065 -0.305054)
			(stroke
				(width 0.1)
				(type default)
			)
			(layer "F.Fab")
		)
		(fp_line
			(start -0.67945 0.3048)
			(end -0.67945 -0.305054)
			(stroke
				(width 0.1)
				(type default)
			)
			(layer "F.Fab")
		)
		(fp_line
			(start -0.12065 -0.305054)
			(end -0.12065 -0.2794)
			(stroke
				(width 0.1)
				(type default)
			)
			(layer "F.Fab")
		)
		(fp_line
			(start -0.12065 -0.2794)
			(end 0.12065 -0.2794)
			(stroke
				(width 0.1)
				(type default)
			)
			(layer "F.Fab")
		)
		(fp_line
			(start -0.12065 0.2794)
			(end -0.12065 0.3048)
			(stroke
				(width 0.1)
				(type default)
			)
			(layer "F.Fab")
		)
		(fp_line
			(start -0.12065 0.3048)
			(end -0.67945 0.3048)
			(stroke
				(width 0.1)
				(type default)
			)
			(layer "F.Fab")
		)
		(fp_line
			(start 0.120396 0.2794)
			(end -0.12065 0.2794)
			(stroke
				(width 0.1)
				(type default)
			)
			(layer "F.Fab")
		)
		(fp_line
			(start 0.120396 0.3048)
			(end 0.120396 0.2794)
			(stroke
				(width 0.1)
				(type default)
			)
			(layer "F.Fab")
		)
		(fp_line
			(start 0.12065 -0.3048)
			(end 0.67945 -0.3048)
			(stroke
				(width 0.1)
				(type default)
			)
			(layer "F.Fab")
		)
		(fp_line
			(start 0.12065 -0.2794)
			(end 0.12065 -0.3048)
			(stroke
				(width 0.1)
				(type default)
			)
			(layer "F.Fab")
		)
		(fp_line
			(start 0.67945 -0.3048)
			(end 0.67945 0.3048)
			(stroke
				(width 0.1)
				(type default)
			)
			(layer "F.Fab")
		)
		(fp_line
			(start 0.67945 0.3048)
			(end 0.120396 0.3048)
			(stroke
				(width 0.1)
				(type default)
			)
			(layer "F.Fab")
		)
		(pad "1" smd circle
			(at -0.40005 0)
			(size 0 0)
			(layers "F.Cu" "F.Mask" "F.Paste")
			(net "SW_P12V_AUX_PVDDIO_P1_FLT")
		)
		(pad "2" smd circle
			(at 0.40005 0)
			(size 0 0)
			(layers "F.Cu" "F.Mask" "F.Paste")
			(net "GND")
		)
	)
	(footprint ""
		(layer "F.Cu")
		(at 396.509748 -16.100298 90)
		(property "Reference" "C1553"
			(at 0 0 90)
			(layer "F.SilkS")
			(hide yes)
			(effects
				(font
					(size 1.27 1.27)
				)
			)
		)
		(property "Value" ""
			(at 0 0 90)
			(layer "F.Fab")
			(effects
				(font
					(size 1.27 1.27)
				)
			)
		)
		(duplicate_pad_numbers_are_jumpers no)
		(fp_line
			(start 0.299974 -0.150114)
			(end 0.299974 0.150114)
			(stroke
				(width 0.1)
				(type default)
			)
			(layer "F.Fab")
		)
		(fp_line
			(start -0.299974 -0.150114)
			(end 0.299974 -0.150114)
			(stroke
				(width 0.1)
				(type default)
			)
			(layer "F.Fab")
		)
		(fp_line
			(start 0.299974 0.150114)
			(end -0.299974 0.150114)
			(stroke
				(width 0.1)
				(type default)
			)
			(layer "F.Fab")
		)
		(fp_line
			(start -0.299974 0.150114)
			(end -0.299974 -0.150114)
			(stroke
				(width 0.1)
				(type default)
			)
			(layer "F.Fab")
		)
		(pad "1" smd rect
			(at -0.2667 0 90)
			(size 0.3048 0.381)
			(layers "F.Cu" "F.Mask" "F.Paste")
			(net "P5E_CPU0_G3_TX_C_DP<13>")
		)
		(pad "2" smd rect
			(at 0.2667 0 90)
			(size 0.3048 0.381)
			(layers "F.Cu" "F.Mask" "F.Paste")
			(net "P5E_CPU0_G3_TX_DP<13>")
		)
	)
	(footprint ""
		(layer "F.Cu")
		(at 22.742906 19.444716 -90)
		(property "Reference" "JP12_12"
			(at 0 0 270)
			(layer "F.SilkS")
			(hide yes)
			(effects
				(font
					(size 1.27 1.27)
				)
			)
		)
		(property "Value" ""
			(at 0 0 270)
			(layer "F.Fab")
			(effects
				(font
					(size 1.27 1.27)
				)
			)
		)
		(duplicate_pad_numbers_are_jumpers no)
		(pad "1" smd circle
			(at 0 0 270)
			(size 0.762 0.762)
			(layers "F.Cu" "F.Mask" "F.Paste")
			(net "Net_10794")
		)
	)
)
